(kicad_pcb
	(version 20241229)
	(generator "pcbnew")
	(generator_version "9.0")
	(general
		(thickness 1.62)
		(legacy_teardrops no)
	)
	(paper "A3")
	(title_block
		(title "COM Express 7 Baseboard")
		(date "2025-02-04")
		(rev "1.1.2")
		(company "Antmicro Ltd")
		(comment 1 "www.antmicro.com")
		(comment 9 "footprints 513-518 of 802")
	)
	(layers
		(0 "F.Cu" signal)
		(4 "In1.Cu" signal)
		(6 "In2.Cu" signal)
		(8 "In3.Cu" signal)
		(10 "In4.Cu" signal)
		(12 "In5.Cu" signal)
		(14 "In6.Cu" signal)
		(2 "B.Cu" signal)
		(9 "F.Adhes" user "F.Adhesive")
		(11 "B.Adhes" user "B.Adhesive")
		(13 "F.Paste" user)
		(15 "B.Paste" user)
		(5 "F.SilkS" user "F.Silkscreen")
		(7 "B.SilkS" user "B.Silkscreen")
		(1 "F.Mask" user)
		(3 "B.Mask" user)
		(17 "Dwgs.User" user "User.Drawings")
		(19 "Cmts.User" user "User.Comments")
		(21 "Eco1.User" user "User.Eco1")
		(23 "Eco2.User" user "User.Eco2")
		(25 "Edge.Cuts" user)
		(27 "Margin" user)
		(31 "F.CrtYd" user "F.Courtyard")
		(29 "B.CrtYd" user "B.Courtyard")
		(35 "F.Fab" user)
		(33 "B.Fab" user)
	)
	(footprint "antmicro-footprints:R_0402_1005Metric"
		(layer "F.Cu")
		(at 192.910913 140.884241 135)
		(descr "Resistor SMD 0402")
		(tags "resistor SMD 0402")
		(property "Reference" "R224"
			(at -1.064088 0.394744 135)
			(layer "F.SilkS")
			(effects
				(font
					(size 0.7 0.7)
					(thickness 0.15)
				)
				(justify left top)
			)
		)
		(property "Value" "R_1k_0402"
			(at -1.011843 1.772046 135)
			(layer "F.Fab")
			(effects
				(font
					(size 0.7 0.7)
					(thickness 0.15)
				)
				(justify left top)
			)
		)
		(property "Datasheet" "https://www.bourns.com/docs/product-datasheets/cr.pdf"
			(at 0 0 135)
			(layer "B.Fab")
			(hide yes)
			(effects
				(font
					(size 1.27 1.27)
					(thickness 0.15)
				)
				(justify mirror)
			)
		)
		(property "Author" "Antmicro"
			(at 331.56 54.689999 45)
			(layer "F.Fab")
			(hide yes)
			(effects
				(font
					(size 1 1)
					(thickness 0.15)
				)
			)
		)
		(property "License" "Apache-2.0"
			(at 331.56 54.689999 45)
			(layer "F.Fab")
			(hide yes)
			(effects
				(font
					(size 1 1)
					(thickness 0.15)
				)
			)
		)
		(property "MPN" "CR0402-FX-1001GLF"
			(at 331.56 54.689999 45)
			(layer "F.Fab")
			(hide yes)
			(effects
				(font
					(size 1 1)
					(thickness 0.15)
				)
			)
		)
		(property "Manufacturer" "Bourns"
			(at 331.56 54.689999 45)
			(layer "F.Fab")
			(hide yes)
			(effects
				(font
					(size 1 1)
					(thickness 0.15)
				)
			)
		)
		(property "Public" "False"
			(at 331.56 54.689999 45)
			(layer "F.Fab")
			(hide yes)
			(effects
				(font
					(size 1 1)
					(thickness 0.15)
				)
			)
		)
		(property "Tolerance" "1%"
			(at 331.56 54.689999 45)
			(layer "F.Fab")
			(hide yes)
			(effects
				(font
					(size 1 1)
					(thickness 0.15)
				)
			)
		)
		(property "Val" "1k"
			(at 331.56 54.689999 45)
			(layer "F.Fab")
			(hide yes)
			(effects
				(font
					(size 1 1)
					(thickness 0.15)
				)
			)
		)
		(sheetname "PCIe redriver")
		(sheetfile "pcie_redriver.kicad_sch")
		(attr smd)
		(fp_poly
			(pts
				(xy -0.925 -0.47) (xy 0.925 -0.47) (xy 0.925 0.47) (xy -0.925 0.47)
			)
			(stroke
				(width 0.05)
				(type default)
			)
			(fill no)
			(layer "F.CrtYd")
		)
		(fp_poly
			(pts
				(xy -0.5 -0.25) (xy 0.5 -0.25) (xy 0.5 0.25) (xy -0.5 0.25)
			)
			(stroke
				(width 0.15)
				(type solid)
			)
			(fill no)
			(layer "F.Fab")
		)
		(pad "1" smd roundrect
			(at -0.48 0 135)
			(size 0.59 0.64)
			(layers "F.Cu" "F.Mask" "F.Paste")
			(roundrect_rratio 0.25)
			(net 1 "GND")
			(pintype "passive")
			(teardrops
				(best_length_ratio 0.2)
				(max_length 1)
				(best_width_ratio 0.9)
				(max_width 2)
				(curved_edges yes)
				(filter_ratio 0.9)
				(enabled yes)
				(allow_two_segments yes)
				(prefer_zone_connections yes)
			)
		)
		(pad "2" smd roundrect
			(at 0.48 0 135)
			(size 0.59 0.64)
			(layers "F.Cu" "F.Mask" "F.Paste")
			(roundrect_rratio 0.25)
			(net 975 "/PCIe redriver/RX_FG0")
			(pintype "passive")
			(teardrops
				(best_length_ratio 0.2)
				(max_length 1)
				(best_width_ratio 0.9)
				(max_width 2)
				(curved_edges yes)
				(filter_ratio 0.9)
				(enabled yes)
				(allow_two_segments yes)
				(prefer_zone_connections yes)
			)
		)
	)
	(footprint "antmicro-footprints:R_0402_1005Metric"
		(layer "F.Cu")
		(at 112.9 146.86 180)
		(descr "Resistor SMD 0402")
		(tags "resistor SMD 0402")
		(property "Reference" "R205"
			(at 0.85 -0.45 0)
			(layer "F.SilkS")
			(effects
				(font
					(size 0.7 0.7)
					(thickness 0.15)
				)
				(justify right bottom)
			)
		)
		(property "Value" "R_1k_0402"
			(at -1.011843 1.772047 0)
			(layer "F.Fab")
			(effects
				(font
					(size 0.7 0.7)
					(thickness 0.15)
				)
				(justify right bottom)
			)
		)
		(property "Datasheet" "https://www.bourns.com/docs/product-datasheets/cr.pdf"
			(at 0 0 180)
			(layer "F.Fab")
			(hide yes)
			(effects
				(font
					(size 1.27 1.27)
					(thickness 0.15)
				)
			)
		)
		(property "Author" "Antmicro"
			(at 225.8 293.72 0)
			(layer "F.Fab")
			(hide yes)
			(effects
				(font
					(size 1 1)
					(thickness 0.15)
				)
			)
		)
		(property "License" "Apache-2.0"
			(at 225.8 293.72 0)
			(layer "F.Fab")
			(hide yes)
			(effects
				(font
					(size 1 1)
					(thickness 0.15)
				)
			)
		)
		(property "MPN" "CR0402-FX-1001GLF"
			(at 225.8 293.72 0)
			(layer "F.Fab")
			(hide yes)
			(effects
				(font
					(size 1 1)
					(thickness 0.15)
				)
			)
		)
		(property "Manufacturer" "Bourns"
			(at 225.8 293.72 0)
			(layer "F.Fab")
			(hide yes)
			(effects
				(font
					(size 1 1)
					(thickness 0.15)
				)
			)
		)
		(property "Public" "False"
			(at 225.8 293.72 0)
			(layer "F.Fab")
			(hide yes)
			(effects
				(font
					(size 1 1)
					(thickness 0.15)
				)
			)
		)
		(property "Tolerance" "1%"
			(at 225.8 293.72 0)
			(layer "F.Fab")
			(hide yes)
			(effects
				(font
					(size 1 1)
					(thickness 0.15)
				)
			)
		)
		(property "Val" "1k"
			(at 225.8 293.72 0)
			(layer "F.Fab")
			(hide yes)
			(effects
				(font
					(size 1 1)
					(thickness 0.15)
				)
			)
		)
		(sheetname "PCIe redriver")
		(sheetfile "pcie_redriver.kicad_sch")
		(attr smd)
		(fp_rect
			(start -0.925 -0.47)
			(end 0.925 0.47)
			(stroke
				(width 0.05)
				(type default)
			)
			(fill no)
			(layer "F.CrtYd")
		)
		(fp_rect
			(start -0.5 -0.25)
			(end 0.5 0.25)
			(stroke
				(width 0.15)
				(type solid)
			)
			(fill no)
			(layer "F.Fab")
		)
		(pad "1" smd roundrect
			(at -0.48 0 180)
			(size 0.59 0.64)
			(layers "F.Cu" "F.Mask" "F.Paste")
			(roundrect_rratio 0.25)
			(net 1 "GND")
			(pintype "passive")
			(teardrops
				(best_length_ratio 0.2)
				(max_length 1)
				(best_width_ratio 0.9)
				(max_width 2)
				(curved_edges yes)
				(filter_ratio 0.9)
				(enabled yes)
				(allow_two_segments yes)
				(prefer_zone_connections yes)
			)
		)
		(pad "2" smd roundrect
			(at 0.48 0 180)
			(size 0.59 0.64)
			(layers "F.Cu" "F.Mask" "F.Paste")
			(roundrect_rratio 0.25)
			(net 624 "/PCIe redriver/TX_EQ1")
			(pintype "passive")
			(teardrops
				(best_length_ratio 0.2)
				(max_length 1)
				(best_width_ratio 0.9)
				(max_width 2)
				(curved_edges yes)
				(filter_ratio 0.9)
				(enabled yes)
				(allow_two_segments yes)
				(prefer_zone_connections yes)
			)
		)
	)
	(footprint "antmicro-footprints:TP_SMD_0.75mm"
		(layer "F.Cu")
		(at 186.70861 72.802163 -90)
		(property "Reference" "TP101"
			(at 0 -0.6 90)
			(layer "F.SilkS")
			(hide yes)
			(effects
				(font
					(size 0.7 0.7)
					(thickness 0.15)
				)
				(justify right bottom)
			)
		)
		(property "Value" "TP_0.75mm_SMD"
			(at 0 1.2 90)
			(layer "F.Fab")
			(effects
				(font
					(size 0.7 0.7)
					(thickness 0.15)
				)
				(justify right bottom)
			)
		)
		(property "Author" "Antmicro"
			(at 113.906447 259.510773 0)
			(layer "F.Fab")
			(hide yes)
			(effects
				(font
					(size 1 1)
					(thickness 0.15)
				)
			)
		)
		(property "License" "Apache-2.0"
			(at 113.906447 259.510773 0)
			(layer "F.Fab")
			(hide yes)
			(effects
				(font
					(size 1 1)
					(thickness 0.15)
				)
			)
		)
		(property "MPN" ""
			(at 113.906447 259.510773 0)
			(layer "F.Fab")
			(hide yes)
			(effects
				(font
					(size 1 1)
					(thickness 0.15)
				)
			)
		)
		(property "Manufacturer" ""
			(at 113.906447 259.510773 0)
			(layer "F.Fab")
			(hide yes)
			(effects
				(font
					(size 1 1)
					(thickness 0.15)
				)
			)
		)
		(property "Public" "False"
			(at 113.906447 259.510773 0)
			(layer "F.Fab")
			(hide yes)
			(effects
				(font
					(size 1 1)
					(thickness 0.15)
				)
			)
		)
		(sheetname "Power")
		(sheetfile "power.kicad_sch")
		(attr exclude_from_pos_files exclude_from_bom)
		(fp_circle
			(center 0 0)
			(end 0.475 0)
			(stroke
				(width 0.05)
				(type default)
			)
			(fill no)
			(layer "F.CrtYd")
		)
		(pad "1" smd circle
			(at 0 0 270)
			(size 0.75 0.75)
			(layers "F.Cu" "F.Mask")
			(net 62 "+12V_AON")
			(pinfunction "1")
			(pintype "passive")
			(teardrops
				(best_length_ratio 0.4)
				(max_length 1)
				(best_width_ratio 0.9)
				(max_width 2)
				(curved_edges yes)
				(filter_ratio 0.9)
				(enabled yes)
				(allow_two_segments yes)
				(prefer_zone_connections yes)
			)
		)
	)
	(footprint "antmicro-footprints:C_0402_1005Metric"
		(layer "F.Cu")
		(at 247.350001 128.310001 -90)
		(descr "Capacitor SMD 0402")
		(tags "capacitor SMD 0402")
		(property "Reference" "C101"
			(at -3.650001 -0.399999 90)
			(layer "F.SilkS")
			(effects
				(font
					(size 0.7 0.7)
					(thickness 0.15)
				)
				(justify right bottom)
			)
		)
		(property "Value" "C_1u_25V_0402"
			(at -1.022927 2.155213 90)
			(layer "F.Fab")
			(effects
				(font
					(size 0.7 0.7)
					(thickness 0.15)
				)
				(justify right bottom)
			)
		)
		(property "Datasheet" "https://www.murata.com/products/productdetail?partno=GRM155R61E105KE11%23"
			(at 0 0 270)
			(layer "F.Fab")
			(hide yes)
			(effects
				(font
					(size 1.27 1.27)
					(thickness 0.15)
				)
			)
		)
		(property "Description" "SMD Multilayer Ceramic Capacitor, 1 µF, 25 V, 0402 [1005 Metric], ± 10%, X5R, GRM Series"
			(at 0 0 270)
			(layer "F.Fab")
			(hide yes)
			(effects
				(font
					(size 1.27 1.27)
					(thickness 0.15)
				)
			)
		)
		(property "Author" "Antmicro"
			(at 119.04 375.660002 0)
			(layer "F.Fab")
			(hide yes)
			(effects
				(font
					(size 1 1)
					(thickness 0.15)
				)
			)
		)
		(property "Dielectric" "X5R"
			(at 119.04 375.660002 0)
			(layer "F.Fab")
			(hide yes)
			(effects
				(font
					(size 1 1)
					(thickness 0.15)
				)
			)
		)
		(property "License" "Apache-2.0"
			(at 119.04 375.660002 0)
			(layer "F.Fab")
			(hide yes)
			(effects
				(font
					(size 1 1)
					(thickness 0.15)
				)
			)
		)
		(property "MPN" "GRM155R61E105KE11J"
			(at 119.04 375.660002 0)
			(layer "F.Fab")
			(hide yes)
			(effects
				(font
					(size 1 1)
					(thickness 0.15)
				)
			)
		)
		(property "Manufacturer" "Murata"
			(at 119.04 375.660002 0)
			(layer "F.Fab")
			(hide yes)
			(effects
				(font
					(size 1 1)
					(thickness 0.15)
				)
			)
		)
		(property "Val" "1u"
			(at 119.04 375.660002 0)
			(layer "F.Fab")
			(hide yes)
			(effects
				(font
					(size 1 1)
					(thickness 0.15)
				)
			)
		)
		(property "Voltage" "25V"
			(at 119.04 375.660002 0)
			(layer "F.Fab")
			(hide yes)
			(effects
				(font
					(size 1 1)
					(thickness 0.15)
				)
			)
		)
		(sheetname "Com Express 7 MGMT")
		(sheetfile "com_express_7_mgmt.kicad_sch")
		(attr smd)
		(fp_rect
			(start -0.925 -0.47)
			(end 0.925 0.47)
			(stroke
				(width 0.05)
				(type default)
			)
			(fill no)
			(layer "F.CrtYd")
		)
		(fp_line
			(start -0.494 0.248)
			(end -0.494 -0.25)
			(stroke
				(width 0.15)
				(type solid)
			)
			(layer "F.Fab")
		)
		(fp_line
			(start 0.504 0.248)
			(end -0.494 0.248)
			(stroke
				(width 0.15)
				(type solid)
			)
			(layer "F.Fab")
		)
		(fp_line
			(start -0.494 -0.25)
			(end 0.504 -0.25)
			(stroke
				(width 0.15)
				(type solid)
			)
			(layer "F.Fab")
		)
		(fp_line
			(start 0.504 -0.25)
			(end 0.504 0.248)
			(stroke
				(width 0.15)
				(type solid)
			)
			(layer "F.Fab")
		)
		(pad "1" smd roundrect
			(at -0.48 0 270)
			(size 0.59 0.64)
			(layers "F.Cu" "F.Mask" "F.Paste")
			(roundrect_rratio 0.25)
			(net 999 "Net-(C101-Pad1)")
			(pintype "passive")
			(teardrops
				(best_length_ratio 0.2)
				(max_length 1)
				(best_width_ratio 0.9)
				(max_width 2)
				(curved_edges yes)
				(filter_ratio 0.9)
				(enabled yes)
				(allow_two_segments yes)
				(prefer_zone_connections yes)
			)
		)
		(pad "2" smd roundrect
			(at 0.48 0 270)
			(size 0.59 0.64)
			(layers "F.Cu" "F.Mask" "F.Paste")
			(roundrect_rratio 0.25)
			(net 84 "/Com Express 7 MGMT/PWRBTN")
			(pintype "passive")
			(teardrops
				(best_length_ratio 0.2)
				(max_length 1)
				(best_width_ratio 0.9)
				(max_width 2)
				(curved_edges yes)
				(filter_ratio 0.9)
				(enabled yes)
				(allow_two_segments yes)
				(prefer_zone_connections yes)
			)
		)
	)
	(footprint "antmicro-footprints:C_0402_1005Metric"
		(layer "F.Cu")
		(at 302.500001 103.61 180)
		(descr "Capacitor SMD 0402")
		(tags "capacitor SMD 0402")
		(property "Reference" "C204"
			(at -1.399999 0.5 0)
			(layer "F.SilkS")
			(effects
				(font
					(size 0.7 0.7)
					(thickness 0.15)
				)
				(justify right bottom)
			)
		)
		(property "Value" "C_100n_0402"
			(at -1.022927 2.155213 0)
			(layer "F.Fab")
			(effects
				(font
					(size 0.7 0.7)
					(thickness 0.15)
				)
				(justify right bottom)
			)
		)
		(property "Datasheet" "https://www.murata.com/products/productdetail?partno=GRM155R61H104KE14%23"
			(at 0 0 180)
			(layer "F.Fab")
			(hide yes)
			(effects
				(font
					(size 1.27 1.27)
					(thickness 0.15)
				)
			)
		)
		(property "Author" "Antmicro"
			(at 605.000002 207.22 0)
			(layer "F.Fab")
			(hide yes)
			(effects
				(font
					(size 1 1)
					(thickness 0.15)
				)
			)
		)
		(property "Dielectric" "X5R"
			(at 605.000002 207.22 0)
			(layer "F.Fab")
			(hide yes)
			(effects
				(font
					(size 1 1)
					(thickness 0.15)
				)
			)
		)
		(property "License" "Apache-2.0"
			(at 605.000002 207.22 0)
			(layer "F.Fab")
			(hide yes)
			(effects
				(font
					(size 1 1)
					(thickness 0.15)
				)
			)
		)
		(property "MPN" "GRM155R61H104KE14D"
			(at 605.000002 207.22 0)
			(layer "F.Fab")
			(hide yes)
			(effects
				(font
					(size 1 1)
					(thickness 0.15)
				)
			)
		)
		(property "Manufacturer" "Murata"
			(at 605.000002 207.22 0)
			(layer "F.Fab")
			(hide yes)
			(effects
				(font
					(size 1 1)
					(thickness 0.15)
				)
			)
		)
		(property "Public" "False"
			(at 605.000002 207.22 0)
			(layer "F.Fab")
			(hide yes)
			(effects
				(font
					(size 1 1)
					(thickness 0.15)
				)
			)
		)
		(property "Val" "100n"
			(at 605.000002 207.22 0)
			(layer "F.Fab")
			(hide yes)
			(effects
				(font
					(size 1 1)
					(thickness 0.15)
				)
			)
		)
		(property "Voltage" "50V"
			(at 605.000002 207.22 0)
			(layer "F.Fab")
			(hide yes)
			(effects
				(font
					(size 1 1)
					(thickness 0.15)
				)
			)
		)
		(sheetname "Power")
		(sheetfile "power.kicad_sch")
		(attr smd)
		(fp_rect
			(start -0.925 -0.47)
			(end 0.925 0.47)
			(stroke
				(width 0.05)
				(type default)
			)
			(fill no)
			(layer "F.CrtYd")
		)
		(fp_line
			(start 0.504 0.248)
			(end -0.494 0.248)
			(stroke
				(width 0.15)
				(type solid)
			)
			(layer "F.Fab")
		)
		(fp_line
			(start 0.504 -0.25)
			(end 0.504 0.248)
			(stroke
				(width 0.15)
				(type solid)
			)
			(layer "F.Fab")
		)
		(fp_line
			(start -0.494 0.248)
			(end -0.494 -0.25)
			(stroke
				(width 0.15)
				(type solid)
			)
			(layer "F.Fab")
		)
		(fp_line
			(start -0.494 -0.25)
			(end 0.504 -0.25)
			(stroke
				(width 0.15)
				(type solid)
			)
			(layer "F.Fab")
		)
		(pad "1" smd roundrect
			(at -0.48 0 180)
			(size 0.59 0.64)
			(layers "F.Cu" "F.Mask" "F.Paste")
			(roundrect_rratio 0.25)
			(net 1 "GND")
			(pintype "passive")
			(teardrops
				(best_length_ratio 0.2)
				(max_length 1)
				(best_width_ratio 0.9)
				(max_width 2)
				(curved_edges yes)
				(filter_ratio 0.9)
				(enabled yes)
				(allow_two_segments yes)
				(prefer_zone_connections yes)
			)
		)
		(pad "2" smd roundrect
			(at 0.48 0 180)
			(size 0.59 0.64)
			(layers "F.Cu" "F.Mask" "F.Paste")
			(roundrect_rratio 0.25)
			(net 73 "+3V3_AON")
			(pintype "passive")
			(teardrops
				(best_length_ratio 0.2)
				(max_length 1)
				(best_width_ratio 0.9)
				(max_width 2)
				(curved_edges yes)
				(filter_ratio 0.9)
				(enabled yes)
				(allow_two_segments yes)
				(prefer_zone_connections yes)
			)
		)
	)
	(footprint "antmicro-footprints:R_0402_1005Metric"
		(layer "F.Cu")
		(at 259.12 161.08 -90)
		(descr "Resistor SMD 0402")
		(tags "resistor SMD 0402")
		(property "Reference" "R179"
			(at -3.65 -0.45 90)
			(layer "F.SilkS")
			(effects
				(font
					(size 0.7 0.7)
					(thickness 0.15)
				)
				(justify right bottom)
			)
		)
		(property "Value" "R_1k_0402"
			(at -1.011843 1.772046 90)
			(layer "F.Fab")
			(effects
				(font
					(size 0.7 0.7)
					(thickness 0.15)
				)
				(justify right bottom)
			)
		)
		(property "Datasheet" "https://www.bourns.com/docs/product-datasheets/cr.pdf"
			(at 0 0 90)
			(layer "F.Fab")
			(hide yes)
			(effects
				(font
					(size 1.27 1.27)
					(thickness 0.15)
				)
			)
		)
		(property "Author" "Antmicro"
			(at 337.8 293.82 90)
			(layer "F.Fab")
			(hide yes)
			(effects
				(font
					(size 1 1)
					(thickness 0.15)
				)
			)
		)
		(property "License" "Apache-2.0"
			(at 337.8 293.82 90)
			(layer "F.Fab")
			(hide yes)
			(effects
				(font
					(size 1 1)
					(thickness 0.15)
				)
			)
		)
		(property "MPN" "CR0402-FX-1001GLF"
			(at 337.8 293.82 90)
			(layer "F.Fab")
			(hide yes)
			(effects
				(font
					(size 1 1)
					(thickness 0.15)
				)
			)
		)
		(property "Manufacturer" "Bourns"
			(at 337.8 293.82 90)
			(layer "F.Fab")
			(hide yes)
			(effects
				(font
					(size 1 1)
					(thickness 0.15)
				)
			)
		)
		(property "Public" "False"
			(at 337.8 293.82 90)
			(layer "F.Fab")
			(hide yes)
			(effects
				(font
					(size 1 1)
					(thickness 0.15)
				)
			)
		)
		(property "Tolerance" "1%"
			(at 337.8 293.82 90)
			(layer "F.Fab")
			(hide yes)
			(effects
				(font
					(size 1 1)
					(thickness 0.15)
				)
			)
		)
		(property "Val" "1k"
			(at 337.8 293.82 90)
			(layer "F.Fab")
			(hide yes)
			(effects
				(font
					(size 1 1)
					(thickness 0.15)
				)
			)
		)
		(sheetname "Com Express 7 MGMT")
		(sheetfile "com_express_7_mgmt.kicad_sch")
		(attr smd)
		(fp_rect
			(start -0.925 -0.47)
			(end 0.925 0.47)
			(stroke
				(width 0.05)
				(type default)
			)
			(fill no)
			(layer "F.CrtYd")
		)
		(fp_rect
			(start -0.5 -0.25)
			(end 0.5 0.25)
			(stroke
				(width 0.15)
				(type solid)
			)
			(fill no)
			(layer "F.Fab")
		)
		(pad "1" smd roundrect
			(at -0.48 0 270)
			(size 0.59 0.64)
			(layers "F.Cu" "F.Mask" "F.Paste")
			(roundrect_rratio 0.25)
			(net 600 "Net-(U36-~{HOLD}(D3))")
			(pintype "passive")
			(teardrops
				(best_length_ratio 0.2)
				(max_length 1)
				(best_width_ratio 0.9)
				(max_width 2)
				(curved_edges yes)
				(filter_ratio 0.9)
				(enabled yes)
				(allow_two_segments yes)
				(prefer_zone_connections yes)
			)
		)
		(pad "2" smd roundrect
			(at 0.48 0 270)
			(size 0.59 0.64)
			(layers "F.Cu" "F.Mask" "F.Paste")
			(roundrect_rratio 0.25)
			(net 85 "/Com Express 7 MGMT/MAFS_POWER")
			(pintype "passive")
			(teardrops
				(best_length_ratio 0.2)
				(max_length 1)
				(best_width_ratio 0.9)
				(max_width 2)
				(curved_edges yes)
				(filter_ratio 0.9)
				(enabled yes)
				(allow_two_segments yes)
				(prefer_zone_connections yes)
			)
		)
	)
)
